# SCM (Grand Teton) — schematic netlist excerpt (pin names and nets, part order shuffled) for the footprints in the layout excerpt that follows; sources: Cadence DE-HDL packaged netlist, KiCad conversion of 12092022_DA0F0TMDCD0_F0T_Management_Board_D_brd_V3_OCP.brd

R375  Q_RES  120 1% EMPTY  pkg 0402LF  page 20 : A = M_BMC_DDR4_MBG1 ; B = P1V2_AUX
C44  Q_CAP  4.7UF 25V 10% X6S  pkg C0603  page 15 : A = P3V3_BMC_USB2AV33 ; B = GND

(kicad_pcb
	(version 20260206)
	(generator "pcbnew")
	(generator_version "10.0")
	(general
		(thickness 1.6)
		(legacy_teardrops no)
	)
	(paper "A4")
	(title_block
		(title "12092022_DA0F0TMDCD0_F0T_Management_Board_D_brd_V3_OCP.brd")
		(comment 1 "Grand Teton / footprints 1432-1433 of 1440")
	)
	(layers
		(0 "F.Cu" signal "TOP")
		(4 "In1.Cu" signal "GND")
		(6 "In2.Cu" signal "IN1")
		(8 "In3.Cu" signal "GND1")
		(10 "In4.Cu" signal "IN2")
		(12 "In5.Cu" signal "VCC")
		(14 "In6.Cu" signal "VCC1")
		(16 "In7.Cu" signal "IN3")
		(18 "In8.Cu" signal "GND2")
		(20 "In9.Cu" signal "IN4")
		(22 "In10.Cu" signal "GND3")
		(2 "B.Cu" signal "BOTTOM")
		(9 "F.Adhes" user "F.Adhesive")
		(11 "B.Adhes" user "B.Adhesive")
		(13 "F.Paste" user "Package Geometry/Pastemask Top")
		(15 "B.Paste" user "Package Geometry/Pastemask Bottom")
		(5 "F.SilkS" user "Ref Des/Silkscreen Top")
		(7 "B.SilkS" user "Ref Des/Silkscreen Bottom")
		(1 "F.Mask" user "Board Geometry/Soldermask Top")
		(3 "B.Mask" user "Board Geometry/Soldermask Bottom")
		(17 "Dwgs.User" user "User.Drawings")
		(19 "Cmts.User" user "User.Comments")
		(21 "Eco1.User" user "User.Eco1")
		(23 "Eco2.User" user "User.Eco2")
		(25 "Edge.Cuts" user "Board Geometry/Outline")
		(27 "Margin" user)
		(31 "F.CrtYd" user "Package Geometry/Place Bound Top")
		(29 "B.CrtYd" user "Package Geometry/Place Bound Bottom")
		(35 "F.Fab" user "Ref Des/Assembly Top")
		(33 "B.Fab" user "Ref Des/Assembly Bottom")
	)
	(footprint ""
		(layer "B.Cu")
		(at 71.1708 -34.8996 180)
		(property "Reference" "C44"
			(at 0 0 0)
			(layer "B.SilkS")
			(hide yes)
			(effects
				(font
					(size 1.27 1.27)
				)
				(justify mirror)
			)
		)
		(property "Value" ""
			(at 0 0 0)
			(layer "B.Fab")
			(effects
				(font
					(size 1.27 1.27)
				)
				(justify mirror)
			)
		)
		(duplicate_pad_numbers_are_jumpers no)
		(fp_line
			(start 1.2954 0.5842)
			(end 1.2954 -0.5842)
			(stroke
				(width 0.1524)
				(type default)
			)
			(layer "B.SilkS")
		)
		(fp_line
			(start 1.2954 -0.5842)
			(end -1.2954 -0.5842)
			(stroke
				(width 0.1524)
				(type default)
			)
			(layer "B.SilkS")
		)
		(fp_line
			(start 0 -0.5842)
			(end 0 0.5842)
			(stroke
				(width 0.1524)
				(type default)
			)
			(layer "B.SilkS")
		)
		(fp_line
			(start -1.2954 0.5842)
			(end 1.2954 0.5842)
			(stroke
				(width 0.1524)
				(type default)
			)
			(layer "B.SilkS")
		)
		(fp_line
			(start -1.2954 -0.5842)
			(end -1.2954 0.5842)
			(stroke
				(width 0.1524)
				(type default)
			)
			(layer "B.SilkS")
		)
		(fp_line
			(start 1.1938 0.4064)
			(end 1.1938 -0.4064)
			(stroke
				(width 0.1)
				(type default)
			)
			(layer "B.Fab")
		)
		(fp_line
			(start 1.1938 -0.4064)
			(end 0.8636 -0.4064)
			(stroke
				(width 0.1)
				(type default)
			)
			(layer "B.Fab")
		)
		(fp_line
			(start 0.8636 0.4572)
			(end 0.8636 0.4064)
			(stroke
				(width 0.1)
				(type default)
			)
			(layer "B.Fab")
		)
		(fp_line
			(start 0.8636 0.4064)
			(end 1.1938 0.4064)
			(stroke
				(width 0.1)
				(type default)
			)
			(layer "B.Fab")
		)
		(fp_line
			(start 0.8636 -0.4064)
			(end 0.8636 -0.4572)
			(stroke
				(width 0.1)
				(type default)
			)
			(layer "B.Fab")
		)
		(fp_line
			(start 0.8636 -0.4572)
			(end -0.8636 -0.4572)
			(stroke
				(width 0.1)
				(type default)
			)
			(layer "B.Fab")
		)
		(fp_line
			(start -0.8636 0.4572)
			(end 0.8636 0.4572)
			(stroke
				(width 0.1)
				(type default)
			)
			(layer "B.Fab")
		)
		(fp_line
			(start -0.8636 0.4064)
			(end -0.8636 0.4572)
			(stroke
				(width 0.1)
				(type default)
			)
			(layer "B.Fab")
		)
		(fp_line
			(start -0.8636 -0.4064)
			(end -1.1938 -0.4064)
			(stroke
				(width 0.1)
				(type default)
			)
			(layer "B.Fab")
		)
		(fp_line
			(start -0.8636 -0.4572)
			(end -0.8636 -0.4064)
			(stroke
				(width 0.1)
				(type default)
			)
			(layer "B.Fab")
		)
		(fp_line
			(start -1.1938 0.4064)
			(end -0.8636 0.4064)
			(stroke
				(width 0.1)
				(type default)
			)
			(layer "B.Fab")
		)
		(fp_line
			(start -1.1938 -0.4064)
			(end -1.1938 0.4064)
			(stroke
				(width 0.1)
				(type default)
			)
			(layer "B.Fab")
		)
		(pad "1" smd rect
			(at 0.7366 0 90)
			(size 0.7112 0.8128)
			(layers "B.Cu" "B.Mask" "B.Paste")
			(net "P3V3_BMC_USB2AV33")
		)
		(pad "2" smd rect
			(at -0.7366 0 90)
			(size 0.7112 0.8128)
			(layers "B.Cu" "B.Mask" "B.Paste")
			(net "GND")
		)
	)
	(footprint ""
		(layer "B.Cu")
		(at 81.38922 -46.586394)
		(property "Reference" "R375"
			(at 0 0 0)
			(layer "B.SilkS")
			(hide yes)
			(effects
				(font
					(size 1.27 1.27)
				)
				(justify mirror)
			)
		)
		(property "Value" ""
			(at 0 0 0)
			(layer "B.Fab")
			(effects
				(font
					(size 1.27 1.27)
				)
				(justify mirror)
			)
		)
		(duplicate_pad_numbers_are_jumpers no)
		(fp_line
			(start -0.7874 -0.4064)
			(end -0.7874 0.4064)
			(stroke
				(width 0.1524)
				(type default)
			)
			(layer "B.SilkS")
		)
		(fp_line
			(start -0.7874 0.4064)
			(end 0.7874 0.4064)
			(stroke
				(width 0.1524)
				(type default)
			)
			(layer "B.SilkS")
		)
		(fp_line
			(start 0.7874 -0.4064)
			(end -0.7874 -0.4064)
			(stroke
				(width 0.1524)
				(type default)
			)
			(layer "B.SilkS")
		)
		(fp_line
			(start 0.7874 0.4064)
			(end 0.7874 -0.4064)
			(stroke
				(width 0.1524)
				(type default)
			)
			(layer "B.SilkS")
		)
		(fp_line
			(start -0.67945 -0.3048)
			(end -0.67945 0.3048)
			(stroke
				(width 0.1)
				(type default)
			)
			(layer "B.Fab")
		)
		(fp_line
			(start -0.67945 0.3048)
			(end -0.120396 0.3048)
			(stroke
				(width 0.1)
				(type default)
			)
			(layer "B.Fab")
		)
		(fp_line
			(start -0.12065 -0.3048)
			(end -0.67945 -0.3048)
			(stroke
				(width 0.1)
				(type default)
			)
			(layer "B.Fab")
		)
		(fp_line
			(start -0.12065 -0.2794)
			(end -0.12065 -0.3048)
			(stroke
				(width 0.1)
				(type default)
			)
			(layer "B.Fab")
		)
		(fp_line
			(start -0.120396 0.2794)
			(end 0.12065 0.2794)
			(stroke
				(width 0.1)
				(type default)
			)
			(layer "B.Fab")
		)
		(fp_line
			(start -0.120396 0.3048)
			(end -0.120396 0.2794)
			(stroke
				(width 0.1)
				(type default)
			)
			(layer "B.Fab")
		)
		(fp_line
			(start 0.12065 -0.305054)
			(end 0.12065 -0.2794)
			(stroke
				(width 0.1)
				(type default)
			)
			(layer "B.Fab")
		)
		(fp_line
			(start 0.12065 -0.2794)
			(end -0.12065 -0.2794)
			(stroke
				(width 0.1)
				(type default)
			)
			(layer "B.Fab")
		)
		(fp_line
			(start 0.12065 0.2794)
			(end 0.12065 0.3048)
			(stroke
				(width 0.1)
				(type default)
			)
			(layer "B.Fab")
		)
		(fp_line
			(start 0.12065 0.3048)
			(end 0.67945 0.3048)
			(stroke
				(width 0.1)
				(type default)
			)
			(layer "B.Fab")
		)
		(fp_line
			(start 0.67945 -0.305054)
			(end 0.12065 -0.305054)
			(stroke
				(width 0.1)
				(type default)
			)
			(layer "B.Fab")
		)
		(fp_line
			(start 0.67945 0.3048)
			(end 0.67945 -0.305054)
			(stroke
				(width 0.1)
				(type default)
			)
			(layer "B.Fab")
		)
		(pad "1" smd circle
			(at 0.40005 0 180)
			(size 0 0)
			(layers "B.Cu" "B.Mask" "B.Paste")
			(net "M_BMC_DDR4_MBG1")
		)
		(pad "2" smd circle
			(at -0.40005 0 180)
			(size 0 0)
			(layers "B.Cu" "B.Mask" "B.Paste")
			(net "P1V2_AUX")
		)
	)
)
